(kicad_pcb
	(version 20260206)
	(generator "pcbnew")
	(generator_version "10.0")
	(general
		(thickness 1.6)
		(legacy_teardrops no)
	)
	(paper "A4")
	(title_block
		(title "panther-plus-userver — 13130-1b_20150205.brd")
		(comment 1 "Honey Badger (Wiwynn) / footprints 373-379 of 1509")
	)
	(layers
		(0 "F.Cu" signal "TOP")
		(4 "In1.Cu" signal "L2")
		(6 "In2.Cu" signal "L3")
		(8 "In3.Cu" signal "L4")
		(10 "In4.Cu" signal "L5")
		(12 "In5.Cu" signal "L6")
		(14 "In6.Cu" signal "L7")
		(16 "In7.Cu" signal "L8")
		(18 "In8.Cu" signal "L9")
		(20 "In9.Cu" signal "L10")
		(22 "In10.Cu" signal "L11")
		(2 "B.Cu" signal "BOTTOM")
		(9 "F.Adhes" user "F.Adhesive")
		(11 "B.Adhes" user "B.Adhesive")
		(13 "F.Paste" user "Package Geometry/Pastemask Top")
		(15 "B.Paste" user "Package Geometry/Pastemask Bottom")
		(5 "F.SilkS" user "Ref Des/Silkscreen Top")
		(7 "B.SilkS" user "Ref Des/Silkscreen Bottom")
		(1 "F.Mask" user "Board Geometry/Soldermask Top")
		(3 "B.Mask" user "Board Geometry/Soldermask Bottom")
		(17 "Dwgs.User" user "User.Drawings")
		(19 "Cmts.User" user "User.Comments")
		(21 "Eco1.User" user "User.Eco1")
		(23 "Eco2.User" user "User.Eco2")
		(25 "Edge.Cuts" user "Board Geometry/Outline")
		(27 "Margin" user)
		(31 "F.CrtYd" user "Package Geometry/Place Bound Top")
		(29 "B.CrtYd" user "Package Geometry/Place Bound Bottom")
		(35 "F.Fab" user "Ref Des/Assembly Top")
		(33 "B.Fab" user "Ref Des/Assembly Bottom")
	)
	(footprint ""
		(layer "F.Cu")
		(at 188.341 -22.479 180)
		(property "Reference" "PC114"
			(at 0 0 180)
			(layer "F.SilkS")
			(hide yes)
			(effects
				(font
					(size 1.27 1.27)
				)
			)
		)
		(property "Value" "SCD1U16V2KX-3GP"
			(at 1.1811 -2.7051 180)
			(unlocked yes)
			(layer "F.Fab")
			(hide yes)
			(effects
				(font
					(size 1.016 1.016)
					(thickness 0.1524)
				)
			)
		)
		(property "Device Type" "C402H22"
			(at 1.1811 -4.2291 180)
			(unlocked yes)
			(layer "F.Fab")
			(hide yes)
			(effects
				(font
					(size 1.016 1.016)
					(thickness 0.1524)
				)
			)
		)
		(duplicate_pad_numbers_are_jumpers no)
		(fp_rect
			(start -0.381 0.7366)
			(end 0.381 -0.7366)
			(stroke
				(width 0)
				(type default)
			)
			(fill no)
			(layer "F.CrtYd")
		)
		(fp_rect
			(start -0.381 0.7366)
			(end 0.381 -0.7366)
			(stroke
				(width 0)
				(type default)
			)
			(fill no)
			(layer "F.Fab")
		)
		(pad "1" smd custom
			(at 0 -0.4572 180)
			(size 0.1143 0.1143)
			(layers "F.Cu" "F.Mask" "F.Paste")
			(net "PV_VTT_DDR_B_REFO")
			(options
				(clearance outline)
				(anchor circle)
			)
			(primitives
				(gr_poly
					(pts
						(arc
							(start -0.254 -0.1778)
							(mid -0.239121 -0.213721)
							(end -0.2032 -0.2286)
						)
						(arc
							(start 0.2032 -0.2286)
							(mid 0.239121 -0.213721)
							(end 0.254 -0.1778)
						)
						(arc
							(start 0.254 0.1778)
							(mid 0.239121 0.213721)
							(end 0.2032 0.2286)
						)
						(arc
							(start -0.2032 0.2286)
							(mid -0.239121 0.213721)
							(end -0.254 0.1778)
						)
					)
					(width 0)
					(fill yes)
				)
			)
		)
		(pad "2" smd custom
			(at 0 0.4572 180)
			(size 0.1143 0.1143)
			(layers "F.Cu" "F.Mask" "F.Paste")
			(net "GND")
			(options
				(clearance outline)
				(anchor circle)
			)
			(primitives
				(gr_poly
					(pts
						(arc
							(start -0.254 -0.1778)
							(mid -0.239121 -0.213721)
							(end -0.2032 -0.2286)
						)
						(arc
							(start 0.2032 -0.2286)
							(mid 0.239121 -0.213721)
							(end 0.254 -0.1778)
						)
						(arc
							(start 0.254 0.1778)
							(mid 0.239121 0.213721)
							(end 0.2032 0.2286)
						)
						(arc
							(start -0.2032 0.2286)
							(mid -0.239121 0.213721)
							(end -0.254 0.1778)
						)
					)
					(width 0)
					(fill yes)
				)
			)
		)
	)
	(footprint ""
		(layer "F.Cu")
		(at 27.686 -32.385 180)
		(property "Reference" "PC44"
			(at 0 0 180)
			(layer "F.SilkS")
			(hide yes)
			(effects
				(font
					(size 1.27 1.27)
				)
			)
		)
		(property "Value" "SC22U6D3V3MX-1-GP"
			(at -0.0254 -2.0193 180)
			(unlocked yes)
			(layer "F.Fab")
			(hide yes)
			(effects
				(font
					(size 1.016 1.016)
					(thickness 0.1524)
				)
			)
		)
		(property "Device Type" "C603H40"
			(at -0.0254 -3.5433 180)
			(unlocked yes)
			(layer "F.Fab")
			(hide yes)
			(effects
				(font
					(size 1.016 1.016)
					(thickness 0.1524)
				)
			)
		)
		(duplicate_pad_numbers_are_jumpers no)
		(fp_line
			(start -0.4064 0)
			(end 0.4064 0)
			(stroke
				(width 0.2286)
				(type default)
			)
			(layer "F.SilkS")
		)
		(fp_rect
			(start -0.635 1.1811)
			(end 0.635 -1.1811)
			(stroke
				(width 0)
				(type default)
			)
			(fill no)
			(layer "F.CrtYd")
		)
		(fp_rect
			(start -0.635 1.1811)
			(end 0.635 -1.1811)
			(stroke
				(width 0)
				(type default)
			)
			(fill no)
			(layer "F.Fab")
		)
		(pad "1" smd custom
			(at 0 -0.6604 180)
			(size 0.19685 0.19685)
			(layers "F.Cu" "F.Mask" "F.Paste")
			(net "P1V0")
			(options
				(clearance outline)
				(anchor circle)
			)
			(primitives
				(gr_poly
					(pts
						(arc
							(start 0.508 -0.2921)
							(mid 0.478242 -0.363942)
							(end 0.4064 -0.3937)
						)
						(arc
							(start -0.4064 -0.3937)
							(mid -0.478242 -0.363942)
							(end -0.508 -0.2921)
						)
						(arc
							(start -0.508 0.2921)
							(mid -0.478242 0.363942)
							(end -0.4064 0.3937)
						)
						(arc
							(start 0.4064 0.3937)
							(mid 0.478242 0.363942)
							(end 0.508 0.2921)
						)
					)
					(width 0)
					(fill yes)
				)
			)
		)
		(pad "2" smd custom
			(at 0 0.6604 180)
			(size 0.19685 0.19685)
			(layers "F.Cu" "F.Mask" "F.Paste")
			(net "GND")
			(options
				(clearance outline)
				(anchor circle)
			)
			(primitives
				(gr_poly
					(pts
						(arc
							(start 0.508 -0.2921)
							(mid 0.478242 -0.363942)
							(end 0.4064 -0.3937)
						)
						(arc
							(start -0.4064 -0.3937)
							(mid -0.478242 -0.363942)
							(end -0.508 -0.2921)
						)
						(arc
							(start -0.508 0.2921)
							(mid -0.478242 0.363942)
							(end -0.4064 0.3937)
						)
						(arc
							(start 0.4064 0.3937)
							(mid 0.478242 0.363942)
							(end 0.508 0.2921)
						)
					)
					(width 0)
					(fill yes)
				)
			)
		)
	)
	(footprint ""
		(layer "F.Cu")
		(at 91.948 -13.208)
		(property "Reference" "R458"
			(at 0 0 0)
			(layer "F.SilkS")
			(hide yes)
			(effects
				(font
					(size 1.27 1.27)
				)
			)
		)
		(property "Value" "4K7R2F-GP"
			(at 1.7907 -1.1176 0)
			(unlocked yes)
			(layer "F.Fab")
			(hide yes)
			(effects
				(font
					(size 1.016 1.016)
					(thickness 0.1524)
				)
			)
		)
		(property "Device Type" "R402H16"
			(at 1.7907 -2.6416 0)
			(unlocked yes)
			(layer "F.Fab")
			(hide yes)
			(effects
				(font
					(size 1.016 1.016)
					(thickness 0.1524)
				)
			)
		)
		(duplicate_pad_numbers_are_jumpers no)
		(fp_rect
			(start -0.381 0.8382)
			(end 0.381 -0.8382)
			(stroke
				(width 0)
				(type default)
			)
			(fill no)
			(layer "F.CrtYd")
		)
		(fp_rect
			(start -0.381 0.8382)
			(end 0.381 -0.8382)
			(stroke
				(width 0)
				(type default)
			)
			(fill no)
			(layer "F.Fab")
		)
		(pad "1" smd custom
			(at 0 -0.4318)
			(size 0.127 0.127)
			(layers "F.Cu" "F.Mask" "F.Paste")
			(net "P3V3_STBY")
			(options
				(clearance outline)
				(anchor circle)
			)
			(primitives
				(gr_poly
					(pts
						(arc
							(start -0.2032 -0.2794)
							(mid -0.239121 -0.264521)
							(end -0.254 -0.2286)
						)
						(arc
							(start -0.254 0.2286)
							(mid -0.239121 0.264521)
							(end -0.2032 0.2794)
						)
						(arc
							(start 0.2032 0.2794)
							(mid 0.239121 0.264521)
							(end 0.254 0.2286)
						)
						(arc
							(start 0.254 -0.2286)
							(mid 0.239121 -0.264521)
							(end 0.2032 -0.2794)
						)
					)
					(width 0)
					(fill yes)
				)
			)
		)
		(pad "2" smd custom
			(at 0 0.4318)
			(size 0.127 0.127)
			(layers "F.Cu" "F.Mask" "F.Paste")
			(net "SLOT_ID2")
			(options
				(clearance outline)
				(anchor circle)
			)
			(primitives
				(gr_poly
					(pts
						(arc
							(start -0.2032 -0.2794)
							(mid -0.239121 -0.264521)
							(end -0.254 -0.2286)
						)
						(arc
							(start -0.254 0.2286)
							(mid -0.239121 0.264521)
							(end -0.2032 0.2794)
						)
						(arc
							(start 0.2032 0.2794)
							(mid 0.239121 0.264521)
							(end 0.254 0.2286)
						)
						(arc
							(start 0.254 -0.2286)
							(mid 0.239121 -0.264521)
							(end 0.2032 -0.2794)
						)
					)
					(width 0)
					(fill yes)
				)
			)
		)
	)
	(footprint ""
		(layer "F.Cu")
		(at 64.389 -13.589)
		(property "Reference" "C307"
			(at 0 0 0)
			(layer "F.SilkS")
			(hide yes)
			(effects
				(font
					(size 1.27 1.27)
				)
			)
		)
		(property "Value" "SCD01U16V2KX-3GP"
			(at 1.8923 -1.2065 0)
			(unlocked yes)
			(layer "F.Fab")
			(hide yes)
			(effects
				(font
					(size 1.016 1.016)
					(thickness 0.1524)
				)
			)
		)
		(property "Device Type" "C402H22"
			(at 1.8923 -2.7305 0)
			(unlocked yes)
			(layer "F.Fab")
			(hide yes)
			(effects
				(font
					(size 1.016 1.016)
					(thickness 0.1524)
				)
			)
		)
		(duplicate_pad_numbers_are_jumpers no)
		(fp_rect
			(start -0.381 0.7366)
			(end 0.381 -0.7366)
			(stroke
				(width 0)
				(type default)
			)
			(fill no)
			(layer "F.CrtYd")
		)
		(fp_rect
			(start -0.381 0.7366)
			(end 0.381 -0.7366)
			(stroke
				(width 0)
				(type default)
			)
			(fill no)
			(layer "F.Fab")
		)
		(pad "1" smd custom
			(at 0 -0.4572)
			(size 0.1143 0.1143)
			(layers "F.Cu" "F.Mask" "F.Paste")
			(net "SATA2_RX_DP0")
			(options
				(clearance outline)
				(anchor circle)
			)
			(primitives
				(gr_poly
					(pts
						(arc
							(start -0.254 -0.1778)
							(mid -0.239121 -0.213721)
							(end -0.2032 -0.2286)
						)
						(arc
							(start 0.2032 -0.2286)
							(mid 0.239121 -0.213721)
							(end 0.254 -0.1778)
						)
						(arc
							(start 0.254 0.1778)
							(mid 0.239121 0.213721)
							(end 0.2032 0.2286)
						)
						(arc
							(start -0.2032 0.2286)
							(mid -0.239121 0.213721)
							(end -0.254 0.1778)
						)
					)
					(width 0)
					(fill yes)
				)
			)
		)
		(pad "2" smd custom
			(at 0 0.4572)
			(size 0.1143 0.1143)
			(layers "F.Cu" "F.Mask" "F.Paste")
			(net "SATA2_RX_C_DP0")
			(options
				(clearance outline)
				(anchor circle)
			)
			(primitives
				(gr_poly
					(pts
						(arc
							(start -0.254 -0.1778)
							(mid -0.239121 -0.213721)
							(end -0.2032 -0.2286)
						)
						(arc
							(start 0.2032 -0.2286)
							(mid 0.239121 -0.213721)
							(end 0.254 -0.1778)
						)
						(arc
							(start 0.254 0.1778)
							(mid 0.239121 0.213721)
							(end 0.2032 0.2286)
						)
						(arc
							(start -0.2032 0.2286)
							(mid -0.239121 0.213721)
							(end -0.254 0.1778)
						)
					)
					(width 0)
					(fill yes)
				)
			)
		)
	)
	(footprint ""
		(layer "F.Cu")
		(at 44.9072 -37.719 90)
		(property "Reference" "U46"
			(at 0 0 90)
			(layer "F.SilkS")
			(hide yes)
			(effects
				(font
					(size 1.27 1.27)
				)
			)
		)
		(property "Value" "SNLVC1G17DCKR-GP"
			(at 0 -8.0772 90)
			(unlocked yes)
			(layer "F.Fab")
			(hide yes)
			(effects
				(font
					(size 1.016 1.016)
					(thickness 0.1524)
				)
			)
		)
		(property "Device Type" "SC70-5H44"
			(at 0 -9.6012 90)
			(unlocked yes)
			(layer "F.Fab")
			(hide yes)
			(effects
				(font
					(size 1.016 1.016)
					(thickness 0.1524)
				)
			)
		)
		(duplicate_pad_numbers_are_jumpers no)
		(fp_line
			(start 1.0033 -0.3302)
			(end 1.0033 0.3302)
			(stroke
				(width 0.1524)
				(type default)
			)
			(layer "F.SilkS")
		)
		(fp_line
			(start -1.0033 -0.3302)
			(end 1.0033 -0.3302)
			(stroke
				(width 0.1524)
				(type default)
			)
			(layer "F.SilkS")
		)
		(fp_line
			(start 1.0033 0.3302)
			(end -1.0033 0.3302)
			(stroke
				(width 0.1524)
				(type default)
			)
			(layer "F.SilkS")
		)
		(fp_line
			(start -1.0033 0.3302)
			(end -1.0033 -0.3302)
			(stroke
				(width 0.1524)
				(type default)
			)
			(layer "F.SilkS")
		)
		(fp_poly
			(pts
				(xy -1.0033 1.4859) (xy -1.0033 0.8001) (xy -1.1811 0.8001) (xy -1.1811 -0.8001) (xy -1.0033 -0.8001)
				(xy -1.0033 -1.4859) (xy 1.0033 -1.4859) (xy 1.0033 -0.8001) (xy 1.1811 -0.8001) (xy 1.1811 0.8001)
				(xy 1.0033 0.8001) (xy 1.0033 1.4859) (xy 0.2921 1.4859) (xy 0.2921 0.8001) (xy -0.2921 0.8001)
				(xy -0.2921 1.4859)
			)
			(stroke
				(width 0)
				(type default)
			)
			(fill no)
			(layer "F.CrtYd")
		)
		(fp_poly
			(pts
				(xy -1.0033 1.4859) (xy -1.0033 0.8001) (xy -1.1811 0.8001) (xy -1.1811 -0.8001) (xy -1.0033 -0.8001)
				(xy -1.0033 -1.4859) (xy 1.0033 -1.4859) (xy 1.0033 -0.8001) (xy 1.1811 -0.8001) (xy 1.1811 0.8001)
				(xy 1.0033 0.8001) (xy 1.0033 1.4859) (xy 0.2921 1.4859) (xy 0.2921 0.8001) (xy -0.2921 0.8001)
				(xy -0.2921 1.4859)
			)
			(stroke
				(width 0)
				(type default)
			)
			(fill no)
			(layer "F.Fab")
		)
		(pad "1" smd rect
			(at 0.65024 -0.93472 90)
			(size 0.3556 0.762)
			(layers "F.Cu" "F.Mask" "F.Paste")
			(net "Net_59")
		)
		(pad "2" smd rect
			(at 0 -0.93472 90)
			(size 0.3556 0.762)
			(layers "F.Cu" "F.Mask" "F.Paste")
			(net "XDP_RTEST#")
		)
		(pad "3" smd rect
			(at -0.65024 -0.93472 90)
			(size 0.3556 0.762)
			(layers "F.Cu" "F.Mask" "F.Paste")
			(net "GND")
		)
		(pad "4" smd rect
			(at -0.65024 0.93472 90)
			(size 0.3556 0.762)
			(layers "F.Cu" "F.Mask" "F.Paste")
			(net "XDP_BUF_RTEST#")
		)
		(pad "5" smd rect
			(at 0.65024 0.93472 90)
			(size 0.3556 0.762)
			(layers "F.Cu" "F.Mask" "F.Paste")
			(net "P3V3_STBY")
		)
	)
	(footprint ""
		(layer "F.Cu")
		(at 63.6016 -43.815)
		(property "Reference" "U33"
			(at 0 0 0)
			(layer "F.SilkS")
			(hide yes)
			(effects
				(font
					(size 1.27 1.27)
				)
			)
		)
		(property "Value" "TS5A23157DGSR-GP"
			(at -4.916678 -5.611622 0)
			(unlocked yes)
			(layer "F.Fab")
			(hide yes)
			(effects
				(font
					(size 1.016 1.016)
					(thickness 0.1524)
				)
			)
		)
		(property "Device Type" "MSOP10H44"
			(at -4.916678 -7.135622 0)
			(unlocked yes)
			(layer "F.Fab")
			(hide yes)
			(effects
				(font
					(size 1.016 1.016)
					(thickness 0.1524)
				)
			)
		)
		(duplicate_pad_numbers_are_jumpers no)
		(fp_line
			(start -1.6764 -1.0541)
			(end -1.6764 1.0541)
			(stroke
				(width 0.1524)
				(type default)
			)
			(layer "F.SilkS")
		)
		(fp_line
			(start -1.6764 -1.016)
			(end -1.6764 1.016)
			(stroke
				(width 0.1524)
				(type default)
			)
			(layer "F.SilkS")
		)
		(fp_line
			(start -1.6764 1.0541)
			(end 1.0795 1.0541)
			(stroke
				(width 0.1524)
				(type default)
			)
			(layer "F.SilkS")
		)
		(fp_line
			(start -1.5494 1.143)
			(end -1.5494 2.6289)
			(stroke
				(width 0.4064)
				(type default)
			)
			(layer "F.SilkS")
		)
		(fp_line
			(start -1.397 0)
			(end -1.6764 -0.2794)
			(stroke
				(width 0.1524)
				(type default)
			)
			(layer "F.SilkS")
		)
		(fp_line
			(start -1.397 0)
			(end -1.6764 0.2794)
			(stroke
				(width 0.1524)
				(type default)
			)
			(layer "F.SilkS")
		)
		(fp_line
			(start 1.0795 -1.0541)
			(end -1.6764 -1.0541)
			(stroke
				(width 0.1524)
				(type default)
			)
			(layer "F.SilkS")
		)
		(fp_line
			(start 1.0795 1.0541)
			(end 1.0795 -1.0541)
			(stroke
				(width 0.1524)
				(type default)
			)
			(layer "F.SilkS")
		)
		(fp_rect
			(start -1.7526 2.8321)
			(end 1.7526 -2.8321)
			(stroke
				(width 0)
				(type default)
			)
			(fill no)
			(layer "F.CrtYd")
		)
		(fp_rect
			(start -1.7526 2.8321)
			(end 1.7526 -2.8321)
			(stroke
				(width 0)
				(type default)
			)
			(fill no)
			(layer "F.Fab")
		)
		(pad "1" smd rect
			(at -0.99949 2.0066)
			(size 0.3048 1.397)
			(layers "F.Cu" "F.Mask" "F.Paste")
			(net "SMBUS_SW_EN")
		)
		(pad "2" smd rect
			(at -0.50038 2.0066)
			(size 0.3048 1.397)
			(layers "F.Cu" "F.Mask" "F.Paste")
			(net "SMBUS_HOST_R_CLK")
		)
		(pad "3" smd rect
			(at 0 2.0066)
			(size 0.3048 1.397)
			(layers "F.Cu" "F.Mask" "F.Paste")
			(net "GND")
		)
		(pad "4" smd rect
			(at 0.50038 2.0066)
			(size 0.3048 1.397)
			(layers "F.Cu" "F.Mask" "F.Paste")
			(net "SMBUS_HOST_R_DATA")
		)
		(pad "5" smd rect
			(at 0.99949 2.0066)
			(size 0.3048 1.397)
			(layers "F.Cu" "F.Mask" "F.Paste")
			(net "SMBUS_SW_EN")
		)
		(pad "6" smd rect
			(at 0.99949 -2.0066)
			(size 0.3048 1.397)
			(layers "F.Cu" "F.Mask" "F.Paste")
			(net "SMB_HOST_LV_R_DATA")
		)
		(pad "7" smd rect
			(at 0.50038 -2.0066)
			(size 0.3048 1.397)
			(layers "F.Cu" "F.Mask" "F.Paste")
			(net "FPGA_SMB_HOST_R_DATA")
		)
		(pad "8" smd rect
			(at 0 -2.0066)
			(size 0.3048 1.397)
			(layers "F.Cu" "F.Mask" "F.Paste")
			(net "P3V3_STBY")
		)
		(pad "9" smd rect
			(at -0.50038 -2.0066)
			(size 0.3048 1.397)
			(layers "F.Cu" "F.Mask" "F.Paste")
			(net "FPGA_SMB_HOST_R_CLK")
		)
		(pad "10" smd rect
			(at -0.99949 -2.0066)
			(size 0.3048 1.397)
			(layers "F.Cu" "F.Mask" "F.Paste")
			(net "SMB_HOST_LV_R_CLK")
		)
	)
	(footprint ""
		(layer "F.Cu")
		(at 19.5834 -68.7578)
		(property "Reference" "PR16"
			(at 0 0 0)
			(layer "F.SilkS")
			(hide yes)
			(effects
				(font
					(size 1.27 1.27)
				)
			)
		)
		(property "Value" "3K65R2F-1-GP"
			(at 1.7907 -1.1176 0)
			(unlocked yes)
			(layer "F.Fab")
			(hide yes)
			(effects
				(font
					(size 1.016 1.016)
					(thickness 0.1524)
				)
			)
		)
		(property "Device Type" "R402H16"
			(at 1.7907 -2.6416 0)
			(unlocked yes)
			(layer "F.Fab")
			(hide yes)
			(effects
				(font
					(size 1.016 1.016)
					(thickness 0.1524)
				)
			)
		)
		(duplicate_pad_numbers_are_jumpers no)
		(fp_rect
			(start -0.381 0.8382)
			(end 0.381 -0.8382)
			(stroke
				(width 0)
				(type default)
			)
			(fill no)
			(layer "F.CrtYd")
		)
		(fp_rect
			(start -0.381 0.8382)
			(end 0.381 -0.8382)
			(stroke
				(width 0)
				(type default)
			)
			(fill no)
			(layer "F.Fab")
		)
		(pad "1" smd custom
			(at 0 -0.4318)
			(size 0.127 0.127)
			(layers "F.Cu" "F.Mask" "F.Paste")
			(net "VR_PVNN_ISUMP_R2")
			(options
				(clearance outline)
				(anchor circle)
			)
			(primitives
				(gr_poly
					(pts
						(arc
							(start -0.2032 -0.2794)
							(mid -0.239121 -0.264521)
							(end -0.254 -0.2286)
						)
						(arc
							(start -0.254 0.2286)
							(mid -0.239121 0.264521)
							(end -0.2032 0.2794)
						)
						(arc
							(start 0.2032 0.2794)
							(mid 0.239121 0.264521)
							(end 0.254 0.2286)
						)
						(arc
							(start 0.254 -0.2286)
							(mid 0.239121 -0.264521)
							(end 0.2032 -0.2794)
						)
					)
					(width 0)
					(fill yes)
				)
			)
		)
		(pad "2" smd custom
			(at 0 0.4318)
			(size 0.127 0.127)
			(layers "F.Cu" "F.Mask" "F.Paste")
			(net "VR_PVNN_ISUMP")
			(options
				(clearance outline)
				(anchor circle)
			)
			(primitives
				(gr_poly
					(pts
						(arc
							(start -0.2032 -0.2794)
							(mid -0.239121 -0.264521)
							(end -0.254 -0.2286)
						)
						(arc
							(start -0.254 0.2286)
							(mid -0.239121 0.264521)
							(end -0.2032 0.2794)
						)
						(arc
							(start 0.2032 0.2794)
							(mid 0.239121 0.264521)
							(end 0.254 0.2286)
						)
						(arc
							(start 0.254 -0.2286)
							(mid 0.239121 -0.264521)
							(end 0.2032 -0.2794)
						)
					)
					(width 0)
					(fill yes)
				)
			)
		)
	)
)
